FILE_TYPE = MACRO_DRAWING;
SET COLOR_WIRE YELLOW;
SET COLOR_PROP ORANGE;
SET COLOR_DOT WHITE;
SET COLOR_ARC YELLOW;
SET COLOR_BODY GREEN;
SET COLOR_NOTE PURPLE;
SET PROP_DISPLAY VALUE;
SET PAGE_NUMBER P206;
FORCEADD QUANTA_TITLE_BLOCK_C..1
(4700 -1775);
FORCEPROP 1 LAST CUSTOM_TXT_CDS <NAME_2>
J 0
(1525 -1725);
FORCEPROP 1 LAST CUSTOM_TXT_CDS <NAME_1>
J 0
(1525 -1600);
FORCEPROP 1 LAST CUSTOM_TXT_CDS <Q_NUMBER>
J 0
(3297 -1672);
DISPLAY 1.212766 (3297 -1672);
FORCEPROP 1 LAST CUSTOM_TXT_CDS <Q_PROJ>
J 0
(2318 -1673);
DISPLAY 1.212766 (2318 -1673);
FORCEPROP 1 LAST CUSTOM_TXT_CDS <Q_REV>
J 0
(4516 -1672);
DISPLAY 1.212766 (4516 -1672);
FORCEPROP 1 LAST CUSTOM_TXT_CDS <CON_LAST_MODIFIED>
J 0
(2815 -1760);
DISPLAY 0.978723 (2815 -1760);
FORCEPROP 1 LAST CUSTOM_TXT_CDS <CON_PAGE_NUM> OF <CON_TOTAL_PAGES>
J 0
(4254 -1757);
DISPLAY 0.978723 (4254 -1757);
FORCEPROP 1 LAST Q_DEPT BU9
J 1
(937 -1726);
DISPLAY 1.957447 (937 -1726);
PAINT GREEN (937 -1726);
FORCEPROP 1 LAST Q_TITLE eFUSE - E1S_3
J 0
(-4600 -1725);
DISPLAY 2.446809 (-4600 -1725);
PAINT GREEN (-4600 -1725);
FORCEPROP 2 LAST CDS_LIB pure_quanta
J 0
(4700 -1775);
DISPLAY INVISIBLE (4700 -1775);
FORCEPROP 1 LAST CDS_LMAN_SYM_OUTLINE -9475,6775,100,-125
J 0
(4700 -1775);
DISPLAY 0.468085 (4700 -1775);
PAINT GREEN (4700 -1775);
DISPLAY INVISIBLE (4700 -1775);
FORCEPROP 2 LAST PAGE_BORDER TRUE
J 0
(-3190 3475);
DISPLAY 0.638298 (-3190 3475);
PAINT PINK (-3190 3475);
DISPLAY INVISIBLE (-3190 3475);
FORCEPROP 1 LAST COMMENT_BODY TRUE
J 0
(4712 -1788);
DISPLAY 0.978723 (4712 -1788);
PAINT GREEN (4712 -1788);
DISPLAY INVISIBLE (4712 -1788);
FORCEPROP 2 LAST CDS_XR_PAGE_TITLE CR-207 : @T6G_MB_LIB.T6G(SCH_1):PAGE207
J 0
(-3190 3475);
DISPLAY 0.638298 (-3190 3475);
PAINT PINK (-3190 3475);
DISPLAY INVISIBLE (-3190 3475);
FORCEPROP 2 LAST CUSTOM_TXT_CDS <XR_PAGE_TITLE>
J 0
(-3190 3475);
DISPLAY 0.638298 (-3190 3475);
PAINT PINK (-3190 3475);
DISPLAY INVISIBLE (-3190 3475);
FORCEPROP 0 LAST CDS_CON_LAST_MODIFIED Wed Mar 09 21:44:56 2022
J 0
(2815 -1760);
DISPLAY INVISIBLE (2815 -1760);
QUIT
